# S9S_MB_2U (Grand Teton) — schematic netlist excerpt (pin names and nets, part order shuffled) for the footprints in the layout excerpt that follows; sources: Cadence DE-HDL packaged netlist, KiCad conversion of 03242023_DA0F0TMBIJ0_F0T_Motherboard_J_brd_V01_OCP.brd

C345  Q_CAP  47UF 4V 20% X6S  pkg C0805  page 79 : A = PVCCIN_CPU1 ; B = GND

X30  TP_TDR_4P_FTS  TP_TDR_4P_DIP EMPTY  pkg TH  page 309
  S1  = TDR_DIFF_100_IN6_DP
  P1  = T1_GND
  P2  = T1_GND
  S2  = TDR_DIFF_100_IN6_DN

(kicad_pcb
	(version 20260206)
	(generator "pcbnew")
	(generator_version "10.0")
	(general
		(thickness 1.6)
		(legacy_teardrops no)
	)
	(paper "A4")
	(title_block
		(title "03242023_DA0F0TMBIJ0_F0T_Motherboard_J_brd_V01_OCP.brd")
		(comment 1 "Grand Teton / footprints 4741-4742 of 6105")
	)
	(layers
		(0 "F.Cu" signal "TOP")
		(4 "In1.Cu" signal "GND")
		(6 "In2.Cu" signal "IN1")
		(8 "In3.Cu" signal "GND1")
		(10 "In4.Cu" signal "IN2")
		(12 "In5.Cu" signal "GND2")
		(14 "In6.Cu" signal "IN3")
		(16 "In7.Cu" signal "GND3")
		(18 "In8.Cu" signal "VCC")
		(20 "In9.Cu" signal "VCC1")
		(22 "In10.Cu" signal "GND4")
		(24 "In11.Cu" signal "IN4")
		(26 "In12.Cu" signal "GND5")
		(28 "In13.Cu" signal "IN5")
		(30 "In14.Cu" signal "GND6")
		(32 "In15.Cu" signal "IN6")
		(34 "In16.Cu" signal "GND7")
		(2 "B.Cu" signal "BOTTOM")
		(9 "F.Adhes" user "F.Adhesive")
		(11 "B.Adhes" user "B.Adhesive")
		(13 "F.Paste" user "Package Geometry/Pastemask Top")
		(15 "B.Paste" user "Package Geometry/Pastemask Bottom")
		(5 "F.SilkS" user "Ref Des/Silkscreen Top")
		(7 "B.SilkS" user "Ref Des/Silkscreen Bottom")
		(1 "F.Mask" user "Board Geometry/Soldermask Top")
		(3 "B.Mask" user "Board Geometry/Soldermask Bottom")
		(17 "Dwgs.User" user "User.Drawings")
		(19 "Cmts.User" user "User.Comments")
		(21 "Eco1.User" user "User.Eco1")
		(23 "Eco2.User" user "User.Eco2")
		(25 "Edge.Cuts" user "Board Geometry/Outline")
		(27 "Margin" user)
		(31 "F.CrtYd" user "Package Geometry/Place Bound Top")
		(29 "B.CrtYd" user "Package Geometry/Place Bound Bottom")
		(35 "F.Fab" user "Ref Des/Assembly Top")
		(33 "B.Fab" user "Ref Des/Assembly Bottom")
	)
	(footprint ""
		(layer "B.Cu")
		(at 493.36833 2.324608 90)
		(property "Reference" "X30"
			(at 1.283208 3.38328 270)
			(unlocked yes)
			(layer "B.SilkS")
			(effects
				(font
					(size 0.7874 0.5842)
					(thickness 0.1524)
				)
				(justify left mirror)
			)
		)
		(property "Value" ""
			(at 0 0 90)
			(layer "B.Fab")
			(effects
				(font
					(size 1.27 1.27)
				)
				(justify mirror)
			)
		)
		(property "Device Type" "TP_TDR_4P_FTS_TH-TP_TDR_4P_DIPA"
			(at -1.30175 1.27 0)
			(unlocked yes)
			(layer "B.Fab")
			(hide yes)
			(effects
				(font
					(size 0.635 0.4064)
					(thickness 0.1524)
				)
				(justify mirror)
			)
		)
		(property "User Part Number" "N_A"
			(at -1.30175 1.27 0)
			(unlocked yes)
			(layer "Cmts.User")
			(hide yes)
			(effects
				(font
					(size 0.635 0.4064)
					(thickness 0.1524)
				)
				(justify mirror)
			)
		)
		(duplicate_pad_numbers_are_jumpers no)
		(fp_line
			(start 0 -1.27)
			(end 0 -0.635)
			(stroke
				(width 0.1524)
				(type default)
			)
			(layer "B.SilkS")
		)
		(fp_line
			(start -2.54 -1.27)
			(end 0 -1.27)
			(stroke
				(width 0.1524)
				(type default)
			)
			(layer "B.SilkS")
		)
		(fp_line
			(start -2.54 -1.1303)
			(end -2.54 -1.27)
			(stroke
				(width 0.1524)
				(type default)
			)
			(layer "B.SilkS")
		)
		(fp_line
			(start 0 0.635)
			(end 0 1.905)
			(stroke
				(width 0.1524)
				(type default)
			)
			(layer "B.SilkS")
		)
		(fp_line
			(start -2.54 1.4097)
			(end -2.54 1.1303)
			(stroke
				(width 0.1524)
				(type default)
			)
			(layer "B.SilkS")
		)
		(fp_line
			(start 0 3.175)
			(end 0 3.81)
			(stroke
				(width 0.1524)
				(type default)
			)
			(layer "B.SilkS")
		)
		(fp_line
			(start 0 3.81)
			(end -2.54 3.81)
			(stroke
				(width 0.1524)
				(type default)
			)
			(layer "B.SilkS")
		)
		(fp_line
			(start -2.54 3.81)
			(end -2.54 3.6703)
			(stroke
				(width 0.1524)
				(type default)
			)
			(layer "B.SilkS")
		)
		(fp_poly
			(pts
				(xy 2.285746 -0.762) (xy 2.285746 0.762) (xy 0.761746 0)
			)
			(stroke
				(width 0)
				(type default)
			)
			(fill yes)
			(layer "B.SilkS")
		)
		(fp_line
			(start 0 -1.27)
			(end 0 3.81)
			(stroke
				(width 0.1)
				(type default)
			)
			(layer "B.Fab")
		)
		(fp_line
			(start -2.54 -1.27)
			(end 0 -1.27)
			(stroke
				(width 0.1)
				(type default)
			)
			(layer "B.Fab")
		)
		(fp_line
			(start 0 3.81)
			(end -2.54 3.81)
			(stroke
				(width 0.1)
				(type default)
			)
			(layer "B.Fab")
		)
		(fp_line
			(start -2.54 3.81)
			(end -2.54 -1.27)
			(stroke
				(width 0.1)
				(type default)
			)
			(layer "B.Fab")
		)
		(fp_poly
			(pts
				(xy 0.761746 0) (xy 2.285746 -0.762) (xy 2.285746 0.762)
			)
			(stroke
				(width 0)
				(type default)
			)
			(fill yes)
			(layer "B.Fab")
		)
		(pad "1" thru_hole circle
			(at 0 0 270)
			(size 1.0033 1.0033)
			(drill 0.249936)
			(layers "*.Cu" "*.Mask")
			(remove_unused_layers no)
			(net "TDR_DIFF_100_IN6_DP")
			(clearance 0.10795)
			(padstack
				(mode front_inner_back)
				(layer "Inner"
					(shape circle)
					(size 0.8001 0.8001)
					(clearance 0.1524)
				)
				(layer "B.Cu"
					(shape circle)
					(size 1.0033 1.0033)
					(thermal_gap 0.10795)
					(clearance 0.10795)
				)
			)
		)
		(pad "2" thru_hole circle
			(at -2.54 0 270)
			(size 1.9939 1.9939)
			(drill 0.249936)
			(layers "*.Cu" "*.Mask")
			(remove_unused_layers no)
			(net "T1_GND")
			(clearance 0.10795)
			(padstack
				(mode front_inner_back)
				(layer "Inner"
					(shape circle)
					(size 0.8001 0.8001)
					(clearance 0.1524)
				)
				(layer "B.Cu"
					(shape circle)
					(size 1.9939 1.9939)
					(thermal_gap 0.10795)
					(clearance 0.10795)
				)
			)
		)
		(pad "3" thru_hole circle
			(at -2.54 2.54 270)
			(size 1.9939 1.9939)
			(drill 0.249936)
			(layers "*.Cu" "*.Mask")
			(remove_unused_layers no)
			(net "T1_GND")
			(clearance 0.10795)
			(padstack
				(mode front_inner_back)
				(layer "Inner"
					(shape circle)
					(size 0.8001 0.8001)
					(clearance 0.1524)
				)
				(layer "B.Cu"
					(shape circle)
					(size 1.9939 1.9939)
					(thermal_gap 0.10795)
					(clearance 0.10795)
				)
			)
		)
		(pad "4" thru_hole circle
			(at 0 2.54 270)
			(size 1.0033 1.0033)
			(drill 0.249936)
			(layers "*.Cu" "*.Mask")
			(remove_unused_layers no)
			(net "TDR_DIFF_100_IN6_DN")
			(clearance 0.10795)
			(padstack
				(mode front_inner_back)
				(layer "Inner"
					(shape circle)
					(size 0.8001 0.8001)
					(clearance 0.1524)
				)
				(layer "B.Cu"
					(shape circle)
					(size 1.0033 1.0033)
					(thermal_gap 0.10795)
					(clearance 0.10795)
				)
			)
		)
	)
	(footprint ""
		(layer "B.Cu")
		(at 118.370604 -294.01008)
		(property "Reference" "C345"
			(at 0 0 0)
			(layer "B.SilkS")
			(hide yes)
			(effects
				(font
					(size 1.27 1.27)
				)
				(justify mirror)
			)
		)
		(property "Value" ""
			(at 0 0 0)
			(layer "B.Fab")
			(effects
				(font
					(size 1.27 1.27)
				)
				(justify mirror)
			)
		)
		(duplicate_pad_numbers_are_jumpers no)
		(fp_line
			(start -1.524 -0.762)
			(end -1.524 0.762)
			(stroke
				(width 0.1524)
				(type default)
			)
			(layer "B.SilkS")
		)
		(fp_line
			(start -1.524 0.762)
			(end 1.524 0.762)
			(stroke
				(width 0.1524)
				(type default)
			)
			(layer "B.SilkS")
		)
		(fp_line
			(start 1.524 -0.762)
			(end -1.524 -0.762)
			(stroke
				(width 0.1524)
				(type default)
			)
			(layer "B.SilkS")
		)
		(fp_line
			(start 1.524 0.762)
			(end 1.524 -0.762)
			(stroke
				(width 0.1524)
				(type default)
			)
			(layer "B.SilkS")
		)
		(fp_line
			(start -1.1049 -0.724916)
			(end 1.1049 -0.724916)
			(stroke
				(width 0.1)
				(type default)
			)
			(layer "B.Fab")
		)
		(fp_line
			(start -1.1049 0.724916)
			(end -1.1049 -0.724916)
			(stroke
				(width 0.1)
				(type default)
			)
			(layer "B.Fab")
		)
		(fp_line
			(start 1.1049 -0.724916)
			(end 1.1049 0.724916)
			(stroke
				(width 0.1)
				(type default)
			)
			(layer "B.Fab")
		)
		(fp_line
			(start 1.1049 0.724916)
			(end -1.1049 0.724916)
			(stroke
				(width 0.1)
				(type default)
			)
			(layer "B.Fab")
		)
		(pad "1" smd rect
			(at 0.889 0)
			(size 1.016 1.27)
			(layers "B.Cu" "B.Mask" "B.Paste")
			(net "PVCCIN_CPU1")
		)
		(pad "2" smd rect
			(at -0.889 0)
			(size 1.016 1.27)
			(layers "B.Cu" "B.Mask" "B.Paste")
			(net "GND")
		)
	)
)
